(kicad_pcb
	(version 20240108)
	(generator "pcbnew")
	(generator_version "8.0")
	(general
		(thickness 1.62)
		(legacy_teardrops no)
	)
	(paper "A4")
	(title_block
		(title "Jetson Orin Baseboard")
		(date "2025-03-12")
		(rev "1.3.4")
		(company "Antmicro Ltd")
		(comment 1 "www.antmicro.com")
		(comment 9 "footprints 362-366 of 677")
	)
	(layers
		(0 "F.Cu" signal)
		(1 "In1.Cu" signal)
		(2 "In2.Cu" signal)
		(3 "In3.Cu" signal)
		(4 "In4.Cu" jumper)
		(5 "In5.Cu" signal)
		(6 "In6.Cu" signal)
		(31 "B.Cu" signal)
		(32 "B.Adhes" user "B.Adhesive")
		(33 "F.Adhes" user "F.Adhesive")
		(34 "B.Paste" user)
		(35 "F.Paste" user)
		(36 "B.SilkS" user "B.Silkscreen")
		(37 "F.SilkS" user "F.Silkscreen")
		(38 "B.Mask" user)
		(39 "F.Mask" user)
		(40 "Dwgs.User" user "User.Drawings")
		(41 "Cmts.User" user "User.Comments")
		(42 "Eco1.User" user "User.Eco1")
		(43 "Eco2.User" user "User.Eco2")
		(44 "Edge.Cuts" user)
		(45 "Margin" user)
		(46 "B.CrtYd" user "B.Courtyard")
		(47 "F.CrtYd" user "F.Courtyard")
		(48 "B.Fab" user)
		(49 "F.Fab" user)
	)
	(footprint "antmicro-footprints:C_0402_1005Metric"
		(layer "B.Cu")
		(at 96.49 100.525)
		(descr "Capacitor SMD 0402")
		(tags "capacitor SMD 0402")
		(property "Reference" "C89"
			(at 0.81 1.325 0)
			(layer "B.SilkS")
			(effects
				(font
					(size 0.7 0.7)
					(thickness 0.15)
				)
				(justify left bottom mirror)
			)
		)
		(property "Value" "C_100n_0402"
			(at 0 -1.4 180)
			(layer "B.Fab")
			(effects
				(font
					(size 0.7 0.7)
					(thickness 0.15)
				)
				(justify left bottom mirror)
			)
		)
		(property "Footprint" "antmicro-footprints:C_0402_1005Metric"
			(at 0 0 0)
			(layer "F.Fab")
			(hide yes)
			(effects
				(font
					(size 1.27 1.27)
					(thickness 0.15)
				)
			)
		)
		(property "Datasheet" "https://www.murata.com/products/productdetail?partno=GRM155R61H104KE14%23"
			(at 0 0 0)
			(layer "F.Fab")
			(hide yes)
			(effects
				(font
					(size 1.27 1.27)
					(thickness 0.15)
				)
			)
		)
		(property "Author" "Antmicro"
			(at 0 0 0)
			(layer "B.Fab")
			(hide yes)
			(effects
				(font
					(size 1 1)
					(thickness 0.15)
				)
				(justify mirror)
			)
		)
		(property "Dielectric" "X5R"
			(at 0 0 0)
			(layer "B.Fab")
			(hide yes)
			(effects
				(font
					(size 1 1)
					(thickness 0.15)
				)
				(justify mirror)
			)
		)
		(property "License" "Apache-2.0"
			(at 0 0 0)
			(layer "B.Fab")
			(hide yes)
			(effects
				(font
					(size 1 1)
					(thickness 0.15)
				)
				(justify mirror)
			)
		)
		(property "MPN" "GRM155R61H104KE14D"
			(at 0 0 0)
			(layer "B.Fab")
			(hide yes)
			(effects
				(font
					(size 1 1)
					(thickness 0.15)
				)
				(justify mirror)
			)
		)
		(property "Manufacturer" "Murata"
			(at 0 0 0)
			(layer "B.Fab")
			(hide yes)
			(effects
				(font
					(size 1 1)
					(thickness 0.15)
				)
				(justify mirror)
			)
		)
		(property "Val" "100n"
			(at 0 0 0)
			(layer "B.Fab")
			(hide yes)
			(effects
				(font
					(size 1 1)
					(thickness 0.15)
				)
				(justify mirror)
			)
		)
		(property "Voltage" "50V"
			(at 0 0 0)
			(layer "B.Fab")
			(hide yes)
			(effects
				(font
					(size 1 1)
					(thickness 0.15)
				)
				(justify mirror)
			)
		)
		(sheetname "CSI")
		(sheetfile "csi.kicad_sch")
		(attr smd)
		(fp_rect
			(start -0.925 0.47)
			(end 0.925 -0.47)
			(stroke
				(width 0.05)
				(type default)
			)
			(fill none)
			(layer "B.CrtYd")
		)
		(fp_line
			(start -0.494 -0.248)
			(end 0.504 -0.248)
			(stroke
				(width 0.15)
				(type solid)
			)
			(layer "B.Fab")
		)
		(fp_line
			(start -0.494 0.25)
			(end -0.494 -0.248)
			(stroke
				(width 0.15)
				(type solid)
			)
			(layer "B.Fab")
		)
		(fp_line
			(start 0.504 -0.248)
			(end 0.504 0.25)
			(stroke
				(width 0.15)
				(type solid)
			)
			(layer "B.Fab")
		)
		(fp_line
			(start 0.504 0.25)
			(end -0.494 0.25)
			(stroke
				(width 0.15)
				(type solid)
			)
			(layer "B.Fab")
		)
		(fp_text user "License: Apache-2.0"
			(at -0.932 -5.17 180)
			(layer "B.Fab")
			(hide yes)
			(effects
				(font
					(size 0.7 0.7)
					(thickness 0.15)
				)
				(justify left bottom mirror)
			)
		)
		(fp_text user "${REFERENCE}"
			(at -0.932 -3.168 180)
			(layer "B.Fab")
			(hide yes)
			(effects
				(font
					(size 0.7 0.7)
					(thickness 0.15)
				)
				(justify left bottom mirror)
			)
		)
		(fp_text user "Author: Antmicro"
			(at -0.932 -4.17 180)
			(layer "B.Fab")
			(hide yes)
			(effects
				(font
					(size 0.7 0.7)
					(thickness 0.15)
				)
				(justify left bottom mirror)
			)
		)
		(pad "1" smd roundrect
			(at -0.48 0)
			(size 0.59 0.64)
			(layers "B.Cu" "B.Paste" "B.Mask")
			(roundrect_rratio 0.25)
			(net 1 "GND")
			(pintype "passive")
		)
		(pad "2" smd roundrect
			(at 0.48 0)
			(size 0.59 0.64)
			(layers "B.Cu" "B.Paste" "B.Mask")
			(roundrect_rratio 0.25)
			(net 112 "+1V8")
			(pintype "passive")
		)
	)
	(footprint "antmicro-footprints:C_0402_1005Metric"
		(layer "B.Cu")
		(at 97.45 92.5)
		(descr "Capacitor SMD 0402")
		(tags "capacitor SMD 0402")
		(property "Reference" "C133"
			(at 3.9 0.41 180)
			(layer "B.SilkS")
			(effects
				(font
					(size 0.7 0.7)
					(thickness 0.15)
				)
				(justify left bottom mirror)
			)
		)
		(property "Value" "C_100n_0402"
			(at 0 -1.4 180)
			(layer "B.Fab")
			(effects
				(font
					(size 0.7 0.7)
					(thickness 0.15)
				)
				(justify left bottom mirror)
			)
		)
		(property "Footprint" "antmicro-footprints:C_0402_1005Metric"
			(at 0 0 0)
			(layer "F.Fab")
			(hide yes)
			(effects
				(font
					(size 1.27 1.27)
					(thickness 0.15)
				)
			)
		)
		(property "Datasheet" "https://www.murata.com/products/productdetail?partno=GRM155R61H104KE14%23"
			(at 0 0 0)
			(layer "F.Fab")
			(hide yes)
			(effects
				(font
					(size 1.27 1.27)
					(thickness 0.15)
				)
			)
		)
		(property "Author" "Antmicro"
			(at 0 0 0)
			(layer "B.Fab")
			(hide yes)
			(effects
				(font
					(size 1 1)
					(thickness 0.15)
				)
				(justify mirror)
			)
		)
		(property "Dielectric" "X5R"
			(at 0 0 0)
			(layer "B.Fab")
			(hide yes)
			(effects
				(font
					(size 1 1)
					(thickness 0.15)
				)
				(justify mirror)
			)
		)
		(property "License" "Apache-2.0"
			(at 0 0 0)
			(layer "B.Fab")
			(hide yes)
			(effects
				(font
					(size 1 1)
					(thickness 0.15)
				)
				(justify mirror)
			)
		)
		(property "MPN" "GRM155R61H104KE14D"
			(at 0 0 0)
			(layer "B.Fab")
			(hide yes)
			(effects
				(font
					(size 1 1)
					(thickness 0.15)
				)
				(justify mirror)
			)
		)
		(property "Manufacturer" "Murata"
			(at 0 0 0)
			(layer "B.Fab")
			(hide yes)
			(effects
				(font
					(size 1 1)
					(thickness 0.15)
				)
				(justify mirror)
			)
		)
		(property "Val" "100n"
			(at 0 0 0)
			(layer "B.Fab")
			(hide yes)
			(effects
				(font
					(size 1 1)
					(thickness 0.15)
				)
				(justify mirror)
			)
		)
		(property "Voltage" "50V"
			(at 0 0 0)
			(layer "B.Fab")
			(hide yes)
			(effects
				(font
					(size 1 1)
					(thickness 0.15)
				)
				(justify mirror)
			)
		)
		(sheetname "HDMI")
		(sheetfile "hdmi.kicad_sch")
		(attr smd)
		(fp_rect
			(start -0.925 0.47)
			(end 0.925 -0.47)
			(stroke
				(width 0.05)
				(type default)
			)
			(fill none)
			(layer "B.CrtYd")
		)
		(fp_line
			(start -0.494 -0.248)
			(end 0.504 -0.248)
			(stroke
				(width 0.15)
				(type solid)
			)
			(layer "B.Fab")
		)
		(fp_line
			(start -0.494 0.25)
			(end -0.494 -0.248)
			(stroke
				(width 0.15)
				(type solid)
			)
			(layer "B.Fab")
		)
		(fp_line
			(start 0.504 -0.248)
			(end 0.504 0.25)
			(stroke
				(width 0.15)
				(type solid)
			)
			(layer "B.Fab")
		)
		(fp_line
			(start 0.504 0.25)
			(end -0.494 0.25)
			(stroke
				(width 0.15)
				(type solid)
			)
			(layer "B.Fab")
		)
		(fp_text user "Author: Antmicro"
			(at -0.932 -4.17 180)
			(layer "B.Fab")
			(hide yes)
			(effects
				(font
					(size 0.7 0.7)
					(thickness 0.15)
				)
				(justify left bottom mirror)
			)
		)
		(fp_text user "${REFERENCE}"
			(at -0.932 -3.168 180)
			(layer "B.Fab")
			(hide yes)
			(effects
				(font
					(size 0.7 0.7)
					(thickness 0.15)
				)
				(justify left bottom mirror)
			)
		)
		(fp_text user "License: Apache-2.0"
			(at -0.932 -5.17 180)
			(layer "B.Fab")
			(hide yes)
			(effects
				(font
					(size 0.7 0.7)
					(thickness 0.15)
				)
				(justify left bottom mirror)
			)
		)
		(pad "1" smd roundrect
			(at -0.48 0)
			(size 0.59 0.64)
			(layers "B.Cu" "B.Paste" "B.Mask")
			(roundrect_rratio 0.25)
			(net 667 "/HDMI/DP_MUX_D2+")
			(pintype "passive")
		)
		(pad "2" smd roundrect
			(at 0.48 0)
			(size 0.59 0.64)
			(layers "B.Cu" "B.Paste" "B.Mask")
			(roundrect_rratio 0.25)
			(net 417 "DP1_TXD1_HDMI_TX1_P")
			(pintype "passive")
		)
	)
	(footprint "antmicro-footprints:TP_SMD_0.75mm"
		(layer "B.Cu")
		(at 68.165 118.57 180)
		(property "Reference" "TP29"
			(at 0 0.6 0)
			(layer "B.SilkS")
			(hide yes)
			(effects
				(font
					(size 0.7 0.7)
					(thickness 0.15)
				)
				(justify left bottom mirror)
			)
		)
		(property "Value" "TP_0.75mm_SMD"
			(at 0 -1.2 0)
			(layer "B.Fab")
			(effects
				(font
					(size 0.7 0.7)
					(thickness 0.15)
				)
				(justify left bottom mirror)
			)
		)
		(property "Footprint" "antmicro-footprints:TP_SMD_0.75mm"
			(at 0 0 180)
			(layer "F.Fab")
			(hide yes)
			(effects
				(font
					(size 1.27 1.27)
					(thickness 0.15)
				)
			)
		)
		(property "Author" "Antmicro"
			(at 136.33 237.14 0)
			(layer "B.Fab")
			(hide yes)
			(effects
				(font
					(size 1 1)
					(thickness 0.15)
				)
				(justify mirror)
			)
		)
		(property "License" "Apache-2.0"
			(at 136.33 237.14 0)
			(layer "B.Fab")
			(hide yes)
			(effects
				(font
					(size 1 1)
					(thickness 0.15)
				)
				(justify mirror)
			)
		)
		(property "MPN" ""
			(at 136.33 237.14 0)
			(layer "B.Fab")
			(hide yes)
			(effects
				(font
					(size 1 1)
					(thickness 0.15)
				)
				(justify mirror)
			)
		)
		(property "Manufacturer" ""
			(at 136.33 237.14 0)
			(layer "B.Fab")
			(hide yes)
			(effects
				(font
					(size 1 1)
					(thickness 0.15)
				)
				(justify mirror)
			)
		)
		(sheetname "USB3")
		(sheetfile "usb3.kicad_sch")
		(attr exclude_from_pos_files exclude_from_bom)
		(fp_circle
			(center 0 0)
			(end 0.475 0)
			(stroke
				(width 0.05)
				(type default)
			)
			(fill none)
			(layer "B.CrtYd")
		)
		(fp_text user "Author: Antmicro"
			(at -0.4 -3.901 0)
			(layer "B.Fab")
			(hide yes)
			(effects
				(font
					(size 0.7 0.7)
					(thickness 0.15)
				)
				(justify left bottom mirror)
			)
		)
		(fp_text user "${REFERENCE}"
			(at -0.4 -2.7 0)
			(layer "B.Fab")
			(hide yes)
			(effects
				(font
					(size 0.7 0.7)
					(thickness 0.15)
				)
				(justify left bottom mirror)
			)
		)
		(fp_text user "License: Apache-2.0"
			(at -0.4 -5.101 0)
			(layer "B.Fab")
			(hide yes)
			(effects
				(font
					(size 0.7 0.7)
					(thickness 0.15)
				)
				(justify left bottom mirror)
			)
		)
		(pad "1" smd circle
			(at 0 0 180)
			(size 0.75 0.75)
			(layers "B.Cu" "B.Mask")
			(net 270 "/USB3/USBC1_VBUS")
			(pinfunction "1")
			(pintype "passive")
		)
	)
	(footprint "antmicro-footprints:SOT-523"
		(layer "B.Cu")
		(at 48.5 119.05 -90)
		(property "Reference" "Q21"
			(at 9.14 13.56 180)
			(layer "B.SilkS")
			(effects
				(font
					(size 0.7 0.7)
					(thickness 0.15)
				)
				(justify left bottom mirror)
			)
		)
		(property "Value" "PJE138K"
			(at 0.1 -1.824 90)
			(layer "B.Fab")
			(effects
				(font
					(size 0.7 0.7)
					(thickness 0.15)
				)
				(justify left bottom mirror)
			)
		)
		(property "Footprint" "antmicro-footprints:SOT-523"
			(at 0 0 -90)
			(layer "F.Fab")
			(hide yes)
			(effects
				(font
					(size 1.27 1.27)
					(thickness 0.15)
				)
			)
		)
		(property "Datasheet" "https://www.mouser.com/datasheet/2/1057/PJE138K-1876698.pdf"
			(at 0 0 -90)
			(layer "F.Fab")
			(hide yes)
			(effects
				(font
					(size 1.27 1.27)
					(thickness 0.15)
				)
			)
		)
		(property "Author" "Antmicro"
			(at -70.55 167.55 0)
			(layer "B.Fab")
			(hide yes)
			(effects
				(font
					(size 1 1)
					(thickness 0.15)
				)
				(justify mirror)
			)
		)
		(property "License" "Apache-2.0"
			(at -70.55 167.55 0)
			(layer "B.Fab")
			(hide yes)
			(effects
				(font
					(size 1 1)
					(thickness 0.15)
				)
				(justify mirror)
			)
		)
		(property "MPN" "PJE138K_R1_00001"
			(at -70.55 167.55 0)
			(layer "B.Fab")
			(hide yes)
			(effects
				(font
					(size 1 1)
					(thickness 0.15)
				)
				(justify mirror)
			)
		)
		(property "Manufacturer" "PANJIT"
			(at -70.55 167.55 0)
			(layer "B.Fab")
			(hide yes)
			(effects
				(font
					(size 1 1)
					(thickness 0.15)
				)
				(justify mirror)
			)
		)
		(sheetname "USB Debug, DP")
		(sheetfile "usb.kicad_sch")
		(attr smd)
		(fp_line
			(start -0.277 0.75)
			(end -0.277 0.551)
			(stroke
				(width 0.15)
				(type solid)
			)
			(layer "B.SilkS")
		)
		(fp_line
			(start -0.725 0.551)
			(end -0.927 0.351)
			(stroke
				(width 0.15)
				(type solid)
			)
			(layer "B.SilkS")
		)
		(fp_line
			(start -0.277 0.551)
			(end -0.725 0.551)
			(stroke
				(width 0.15)
				(type solid)
			)
			(layer "B.SilkS")
		)
		(fp_line
			(start -0.927 0.351)
			(end -0.927 0.051)
			(stroke
				(width 0.15)
				(type solid)
			)
			(layer "B.SilkS")
		)
		(fp_circle
			(center -0.9652 -0.9652)
			(end -0.9152 -0.9652)
			(stroke
				(width 0.15)
				(type solid)
			)
			(fill solid)
			(layer "B.SilkS")
		)
		(fp_line
			(start 1.1 1.16)
			(end -1.12 1.16)
			(stroke
				(width 0.05)
				(type solid)
			)
			(layer "B.CrtYd")
		)
		(fp_line
			(start -1.12 -1.15)
			(end -1.12 1.16)
			(stroke
				(width 0.05)
				(type solid)
			)
			(layer "B.CrtYd")
		)
		(fp_line
			(start 1.1 -1.15)
			(end 1.1 1.16)
			(stroke
				(width 0.05)
				(type solid)
			)
			(layer "B.CrtYd")
		)
		(fp_line
			(start 1.1 -1.15)
			(end -1.12 -1.15)
			(stroke
				(width 0.05)
				(type solid)
			)
			(layer "B.CrtYd")
		)
		(fp_line
			(start -0.652 0.425)
			(end 0.8 0.425)
			(stroke
				(width 0.15)
				(type solid)
			)
			(layer "B.Fab")
		)
		(fp_line
			(start -0.802 0.276)
			(end -0.652 0.425)
			(stroke
				(width 0.15)
				(type solid)
			)
			(layer "B.Fab")
		)
		(fp_line
			(start -0.802 -0.424)
			(end -0.802 0.276)
			(stroke
				(width 0.15)
				(type solid)
			)
			(layer "B.Fab")
		)
		(fp_line
			(start -0.802 -0.424)
			(end 0.8 -0.424)
			(stroke
				(width 0.15)
				(type solid)
			)
			(layer "B.Fab")
		)
		(fp_line
			(start 0.8 -0.424)
			(end 0.8 0.425)
			(stroke
				(width 0.15)
				(type solid)
			)
			(layer "B.Fab")
		)
		(fp_circle
			(center -0.9652 -0.9652)
			(end -0.9144 -0.9652)
			(stroke
				(width 0.15)
				(type solid)
			)
			(fill none)
			(layer "B.Fab")
		)
		(fp_text user "License: Apache-2.0"
			(at -1.12 -5.024 90)
			(layer "B.Fab")
			(hide yes)
			(effects
				(font
					(size 0.7 0.7)
					(thickness 0.15)
				)
				(justify left bottom mirror)
			)
		)
		(fp_text user "${REFERENCE}"
			(at -1.12 -3.824 90)
			(layer "B.Fab")
			(hide yes)
			(effects
				(font
					(size 0.7 0.7)
					(thickness 0.15)
				)
				(justify left bottom mirror)
			)
		)
		(fp_text user "Author: Antmicro"
			(at -1.12 -6.224 90)
			(layer "B.Fab")
			(hide yes)
			(effects
				(font
					(size 0.7 0.7)
					(thickness 0.15)
				)
				(justify left bottom mirror)
			)
		)
		(pad "1" smd rect
			(at -0.5 -0.65 270)
			(size 0.4 0.51)
			(layers "B.Cu" "B.Paste" "B.Mask")
			(net 272 "/USB Debug, DP/FTDI_LED_RX")
			(pinfunction "G")
			(pintype "passive")
		)
		(pad "2" smd rect
			(at 0.498 -0.65 270)
			(size 0.4 0.51)
			(layers "B.Cu" "B.Paste" "B.Mask")
			(net 1 "GND")
			(pinfunction "S")
			(pintype "passive")
		)
		(pad "3" smd rect
			(at 0 0.652 270)
			(size 0.4 0.51)
			(layers "B.Cu" "B.Paste" "B.Mask")
			(net 397 "/USB Debug, DP/FTDI_CBUS_EN")
			(pinfunction "D")
			(pintype "passive")
		)
	)
	(footprint "antmicro-footprints:C_0402_1005Metric"
		(layer "B.Cu")
		(at 139.54 97.53 180)
		(descr "Capacitor SMD 0402")
		(tags "capacitor SMD 0402")
		(property "Reference" "C100"
			(at -1.24 0.53 0)
			(layer "B.SilkS")
			(effects
				(font
					(size 0.7 0.7)
					(thickness 0.15)
				)
				(justify left bottom mirror)
			)
		)
		(property "Value" "C_100n_0402"
			(at 0 -1.4 0)
			(layer "B.Fab")
			(effects
				(font
					(size 0.7 0.7)
					(thickness 0.15)
				)
				(justify left bottom mirror)
			)
		)
		(property "Footprint" "antmicro-footprints:C_0402_1005Metric"
			(at 0 0 180)
			(layer "F.Fab")
			(hide yes)
			(effects
				(font
					(size 1.27 1.27)
					(thickness 0.15)
				)
			)
		)
		(property "Datasheet" "https://www.murata.com/products/productdetail?partno=GRM155R61H104KE14%23"
			(at 0 0 180)
			(layer "F.Fab")
			(hide yes)
			(effects
				(font
					(size 1.27 1.27)
					(thickness 0.15)
				)
			)
		)
		(property "Author" "Antmicro"
			(at 279.08 195.06 0)
			(layer "B.Fab")
			(hide yes)
			(effects
				(font
					(size 1 1)
					(thickness 0.15)
				)
				(justify mirror)
			)
		)
		(property "Dielectric" "X5R"
			(at 279.08 195.06 0)
			(layer "B.Fab")
			(hide yes)
			(effects
				(font
					(size 1 1)
					(thickness 0.15)
				)
				(justify mirror)
			)
		)
		(property "License" "Apache-2.0"
			(at 279.08 195.06 0)
			(layer "B.Fab")
			(hide yes)
			(effects
				(font
					(size 1 1)
					(thickness 0.15)
				)
				(justify mirror)
			)
		)
		(property "MPN" "GRM155R61H104KE14D"
			(at 279.08 195.06 0)
			(layer "B.Fab")
			(hide yes)
			(effects
				(font
					(size 1 1)
					(thickness 0.15)
				)
				(justify mirror)
			)
		)
		(property "Manufacturer" "Murata"
			(at 279.08 195.06 0)
			(layer "B.Fab")
			(hide yes)
			(effects
				(font
					(size 1 1)
					(thickness 0.15)
				)
				(justify mirror)
			)
		)
		(property "Val" "100n"
			(at 279.08 195.06 0)
			(layer "B.Fab")
			(hide yes)
			(effects
				(font
					(size 1 1)
					(thickness 0.15)
				)
				(justify mirror)
			)
		)
		(property "Voltage" "50V"
			(at 279.08 195.06 0)
			(layer "B.Fab")
			(hide yes)
			(effects
				(font
					(size 1 1)
					(thickness 0.15)
				)
				(justify mirror)
			)
		)
		(sheetname "CSI")
		(sheetfile "csi.kicad_sch")
		(attr smd)
		(fp_rect
			(start -0.925 0.47)
			(end 0.925 -0.47)
			(stroke
				(width 0.05)
				(type default)
			)
			(fill none)
			(layer "B.CrtYd")
		)
		(fp_line
			(start 0.504 0.25)
			(end -0.494 0.25)
			(stroke
				(width 0.15)
				(type solid)
			)
			(layer "B.Fab")
		)
		(fp_line
			(start 0.504 -0.248)
			(end 0.504 0.25)
			(stroke
				(width 0.15)
				(type solid)
			)
			(layer "B.Fab")
		)
		(fp_line
			(start -0.494 0.25)
			(end -0.494 -0.248)
			(stroke
				(width 0.15)
				(type solid)
			)
			(layer "B.Fab")
		)
		(fp_line
			(start -0.494 -0.248)
			(end 0.504 -0.248)
			(stroke
				(width 0.15)
				(type solid)
			)
			(layer "B.Fab")
		)
		(fp_text user "License: Apache-2.0"
			(at -0.932 -5.17 0)
			(layer "B.Fab")
			(hide yes)
			(effects
				(font
					(size 0.7 0.7)
					(thickness 0.15)
				)
				(justify left bottom mirror)
			)
		)
		(fp_text user "Author: Antmicro"
			(at -0.932 -4.17 0)
			(layer "B.Fab")
			(hide yes)
			(effects
				(font
					(size 0.7 0.7)
					(thickness 0.15)
				)
				(justify left bottom mirror)
			)
		)
		(fp_text user "${REFERENCE}"
			(at -0.932 -3.168 0)
			(layer "B.Fab")
			(hide yes)
			(effects
				(font
					(size 0.7 0.7)
					(thickness 0.15)
				)
				(justify left bottom mirror)
			)
		)
		(pad "1" smd roundrect
			(at -0.48 0 180)
			(size 0.59 0.64)
			(layers "B.Cu" "B.Paste" "B.Mask")
			(roundrect_rratio 0.25)
			(net 1 "GND")
			(pintype "passive")
		)
		(pad "2" smd roundrect
			(at 0.48 0 180)
			(size 0.59 0.64)
			(layers "B.Cu" "B.Paste" "B.Mask")
			(roundrect_rratio 0.25)
			(net 87 "+3V3")
			(pintype "passive")
		)
	)
)
